# BASEBOARD_FAB2 (Tioga Pass) — schematic netlist excerpt (pin names and nets, part order shuffled) for the footprints in the layout excerpt that follows; sources: Cadence DE-HDL packaged netlist, KiCad conversion of Wiwynn_Tioga_Pass_MB.brd

C1F8  CAP  0.22UF 16V 10% X7R  pkg 0402  page 181 : A = P3E_CPU1_PE3_MP_C_TXN<5> ; B = P3E_CPU1_PE3_MP_TXN<5>
R9G34  RES  0.0 5% CHIP  pkg 0402  page 152 : A = H_CPU0_MEMABC_MEMHOT_G_N ; B = H_CPU0_MEMABC_MEMHOT_G_R_N

(kicad_pcb
	(version 20260206)
	(generator "pcbnew")
	(generator_version "10.0")
	(general
		(thickness 1.6)
		(legacy_teardrops no)
	)
	(paper "A4")
	(title_block
		(title "Wiwynn_Tioga_Pass_MB.brd")
		(comment 1 "Tioga Pass / footprints 1463-1464 of 4770")
	)
	(layers
		(0 "F.Cu" signal "TOP")
		(4 "In1.Cu" signal "L2GND")
		(6 "In2.Cu" signal "L3")
		(8 "In3.Cu" signal "L4GND")
		(10 "In4.Cu" signal "L5")
		(12 "In5.Cu" signal "L6GND")
		(14 "In6.Cu" signal "L7VCC")
		(16 "In7.Cu" signal "L8VCC")
		(18 "In8.Cu" signal "L9GND")
		(20 "In9.Cu" signal "L10")
		(22 "In10.Cu" signal "L11GND")
		(24 "In11.Cu" signal "L12")
		(26 "In12.Cu" signal "L13GND")
		(2 "B.Cu" signal "BOTTOM")
		(9 "F.Adhes" user "F.Adhesive")
		(11 "B.Adhes" user "B.Adhesive")
		(13 "F.Paste" user "Package Geometry/Pastemask Top")
		(15 "B.Paste" user "Package Geometry/Pastemask Bottom")
		(5 "F.SilkS" user "Ref Des/Silkscreen Top")
		(7 "B.SilkS" user "Ref Des/Silkscreen Bottom")
		(1 "F.Mask" user "Board Geometry/Soldermask Top")
		(3 "B.Mask" user "Board Geometry/Soldermask Bottom")
		(17 "Dwgs.User" user "User.Drawings")
		(19 "Cmts.User" user "User.Comments")
		(21 "Eco1.User" user "User.Eco1")
		(23 "Eco2.User" user "User.Eco2")
		(25 "Edge.Cuts" user "Board Geometry/Outline")
		(27 "Margin" user)
		(31 "F.CrtYd" user "Package Geometry/Place Bound Top")
		(29 "B.CrtYd" user "Package Geometry/Place Bound Bottom")
		(35 "F.Fab" user "Ref Des/Assembly Top")
		(33 "B.Fab" user "Ref Des/Assembly Bottom")
	)
	(footprint ""
		(layer "F.Cu")
		(at 13.8938 -32.131 90)
		(property "Reference" "C1F8"
			(at 0 0 90)
			(layer "F.SilkS")
			(hide yes)
			(effects
				(font
					(size 1.27 1.27)
				)
			)
		)
		(property "Value" ""
			(at 0 0 90)
			(layer "F.Fab")
			(effects
				(font
					(size 1.27 1.27)
				)
			)
		)
		(duplicate_pad_numbers_are_jumpers no)
		(fp_rect
			(start -0.3048 -0.1016)
			(end 0.3048 0.9906)
			(stroke
				(width 0)
				(type default)
			)
			(fill no)
			(layer "F.CrtYd")
		)
		(fp_line
			(start 0.3048 -0.1016)
			(end -0.3048 -0.1016)
			(stroke
				(width 0.1)
				(type default)
			)
			(layer "F.Fab")
		)
		(fp_line
			(start -0.3048 -0.1016)
			(end -0.3048 0.9906)
			(stroke
				(width 0.1)
				(type default)
			)
			(layer "F.Fab")
		)
		(fp_line
			(start 0.3048 0.9906)
			(end 0.3048 -0.1016)
			(stroke
				(width 0.1)
				(type default)
			)
			(layer "F.Fab")
		)
		(fp_line
			(start -0.3048 0.9906)
			(end 0.3048 0.9906)
			(stroke
				(width 0.1)
				(type default)
			)
			(layer "F.Fab")
		)
		(pad "1" smd rect
			(at 0 0 90)
			(size 0.508 0.508)
			(layers "F.Cu" "F.Mask" "F.Paste")
			(net "P3E_CPU1_PE3_MP_C_TXN<5>")
		)
		(pad "2" smd rect
			(at 0 0.889 90)
			(size 0.508 0.508)
			(layers "F.Cu" "F.Mask" "F.Paste")
			(net "P3E_CPU1_PE3_MP_TXN<5>")
		)
		(zone
			(layer "F.Cu")
			(hatch none 0.5)
			(connect_pads
				(clearance 0)
			)
			(min_thickness 0.25)
			(keepout
				(tracks allowed)
				(vias not_allowed)
				(pads allowed)
				(copperpour not_allowed)
				(footprints allowed)
			)
			(placement
				(enabled no)
				(sheetname "")
			)
			(fill
				(thermal_gap 0.5)
				(thermal_bridge_width 0.5)
				(island_removal_mode 0)
			)
			(polygon
				(pts
					(xy 14.1478 -31.877) (xy 14.5288 -31.877) (xy 14.5288 -32.385) (xy 14.1478 -32.385)
				)
			)
		)
		(zone
			(layer "F.Cu")
			(hatch none 0.5)
			(connect_pads
				(clearance 0)
			)
			(min_thickness 0.25)
			(keepout
				(tracks not_allowed)
				(vias allowed)
				(pads allowed)
				(copperpour not_allowed)
				(footprints allowed)
			)
			(placement
				(enabled no)
				(sheetname "")
			)
			(fill
				(thermal_gap 0.5)
				(thermal_bridge_width 0.5)
				(island_removal_mode 0)
			)
			(polygon
				(pts
					(xy 14.1478 -31.877) (xy 14.5288 -31.877) (xy 14.5288 -32.385) (xy 14.1478 -32.385)
				)
			)
		)
	)
	(footprint ""
		(layer "F.Cu")
		(at 443.253876 -12.599924 90)
		(property "Reference" "R9G34"
			(at 0 0 90)
			(layer "F.SilkS")
			(hide yes)
			(effects
				(font
					(size 1.27 1.27)
				)
			)
		)
		(property "Value" ""
			(at 0 0 90)
			(layer "F.Fab")
			(effects
				(font
					(size 1.27 1.27)
				)
			)
		)
		(duplicate_pad_numbers_are_jumpers no)
		(fp_poly
			(pts
				(xy -0.2794 -0.1016) (xy 0.2794 -0.1016) (xy 0.2794 0.9906) (xy -0.2794 0.9906)
			)
			(stroke
				(width 0)
				(type default)
			)
			(fill no)
			(layer "F.CrtYd")
		)
		(fp_line
			(start 0.2794 -0.1016)
			(end -0.2794 -0.1016)
			(stroke
				(width 0.1)
				(type default)
			)
			(layer "F.Fab")
		)
		(fp_line
			(start -0.2794 -0.1016)
			(end -0.2794 0.9906)
			(stroke
				(width 0.1)
				(type default)
			)
			(layer "F.Fab")
		)
		(fp_line
			(start 0.2794 0.9906)
			(end 0.2794 -0.1016)
			(stroke
				(width 0.1)
				(type default)
			)
			(layer "F.Fab")
		)
		(fp_line
			(start -0.2794 0.9906)
			(end 0.2794 0.9906)
			(stroke
				(width 0.1)
				(type default)
			)
			(layer "F.Fab")
		)
		(pad "1" smd rect
			(at 0 0 90)
			(size 0.508 0.508)
			(layers "F.Cu" "F.Mask" "F.Paste")
			(net "H_CPU0_MEMABC_MEMHOT_G_N")
		)
		(pad "2" smd rect
			(at 0 0.889 90)
			(size 0.508 0.508)
			(layers "F.Cu" "F.Mask" "F.Paste")
			(net "H_CPU0_MEMABC_MEMHOT_G_R_N")
		)
		(zone
			(layer "F.Cu")
			(hatch none 0.5)
			(connect_pads
				(clearance 0)
			)
			(min_thickness 0.25)
			(keepout
				(tracks allowed)
				(vias not_allowed)
				(pads allowed)
				(copperpour not_allowed)
				(footprints allowed)
			)
			(placement
				(enabled no)
				(sheetname "")
			)
			(fill
				(thermal_gap 0.5)
				(thermal_bridge_width 0.5)
				(island_removal_mode 0)
			)
			(polygon
				(pts
					(xy 443.507876 -12.345924) (xy 443.507876 -12.853924) (xy 443.888876 -12.853924) (xy 443.888876 -12.345924)
				)
			)
		)
		(zone
			(layer "F.Cu")
			(hatch none 0.5)
			(connect_pads
				(clearance 0)
			)
			(min_thickness 0.25)
			(keepout
				(tracks not_allowed)
				(vias allowed)
				(pads allowed)
				(copperpour not_allowed)
				(footprints allowed)
			)
			(placement
				(enabled no)
				(sheetname "")
			)
			(fill
				(thermal_gap 0.5)
				(thermal_bridge_width 0.5)
				(island_removal_mode 0)
			)
			(polygon
				(pts
					(xy 443.888876 -12.345924) (xy 443.888876 -12.853924) (xy 443.507876 -12.853924) (xy 443.507876 -12.345924)
				)
			)
		)
	)
)
